(kicad_pcb
	(version 20260206)
	(generator "pcbnew")
	(generator_version "10.0")
	(general
		(thickness 1.6)
		(legacy_teardrops no)
	)
	(paper "A4")
	(title_block
		(title "panther-plus-userver — 13130-1b_20150205.brd")
		(comment 1 "Honey Badger (Wiwynn) / footprint 1214 of 1509 (DIMM3), pads 156-162 of 210")
	)
	(layers
		(0 "F.Cu" signal "TOP")
		(4 "In1.Cu" signal "L2")
		(6 "In2.Cu" signal "L3")
		(8 "In3.Cu" signal "L4")
		(10 "In4.Cu" signal "L5")
		(12 "In5.Cu" signal "L6")
		(14 "In6.Cu" signal "L7")
		(16 "In7.Cu" signal "L8")
		(18 "In8.Cu" signal "L9")
		(20 "In9.Cu" signal "L10")
		(22 "In10.Cu" signal "L11")
		(2 "B.Cu" signal "BOTTOM")
		(9 "F.Adhes" user "F.Adhesive")
		(11 "B.Adhes" user "B.Adhesive")
		(13 "F.Paste" user "Package Geometry/Pastemask Top")
		(15 "B.Paste" user "Package Geometry/Pastemask Bottom")
		(5 "F.SilkS" user "Ref Des/Silkscreen Top")
		(7 "B.SilkS" user "Ref Des/Silkscreen Bottom")
		(1 "F.Mask" user "Board Geometry/Soldermask Top")
		(3 "B.Mask" user "Board Geometry/Soldermask Bottom")
		(17 "Dwgs.User" user "User.Drawings")
		(19 "Cmts.User" user "User.Comments")
		(21 "Eco1.User" user "User.Eco1")
		(23 "Eco2.User" user "User.Eco2")
		(25 "Edge.Cuts" user "Board Geometry/Outline")
		(27 "Margin" user)
		(31 "F.CrtYd" user "Package Geometry/Place Bound Top")
		(29 "B.CrtYd" user "Package Geometry/Place Bound Bottom")
		(35 "F.Fab" user "Ref Des/Assembly Top")
		(33 "B.Fab" user "Ref Des/Assembly Bottom")
	)
	(footprint ""
		(layer "B.Cu")
		(at 159.999934 -5.790692)
		(property "Reference" "DIMM3"
			(at 0 0 0)
			(layer "B.SilkS")
			(hide yes)
			(effects
				(font
					(size 1.27 1.27)
				)
				(justify mirror)
			)
		)
		(property "Value" "DDR3-204P-142-COLAY-1-GP-U"
			(at 41.312338 -16.676878 0)
			(unlocked yes)
			(layer "B.Fab")
			(hide yes)
			(effects
				(font
					(size 1.016 1.016)
					(thickness 0.1524)
				)
				(justify mirror)
			)
		)
		(property "Device Type" "AS0A626-J8R6-7H-COLAY-1"
			(at 41.312338 -18.200878 0)
			(unlocked yes)
			(layer "B.Fab")
			(hide yes)
			(effects
				(font
					(size 1.016 1.016)
					(thickness 0.1524)
				)
				(justify mirror)
			)
		)
		(duplicate_pad_numbers_are_jumpers no)
		(pad "154" smd custom
			(at 16.649954 4.100068 180)
			(size 0.1143 0.1143)
			(layers "B.Cu" "B.Mask" "B.Paste")
			(net "M_B_DQS_DN5")
			(options
				(clearance outline)
				(anchor circle)
			)
			(primitives
				(gr_poly
					(pts
						(xy 0 -0.9017) (xy -0.03175 -0.89916) (xy -0.0635 -0.889) (xy -0.09144 -0.87376) (xy -0.11684 -0.85344)
						(xy -0.13716 -0.82804) (xy -0.1524 -0.8001) (xy -0.16256 -0.76835) (xy -0.1651 -0.7366) (xy -0.1651 0.13462)
						(xy -0.17272 0.14224) (xy -0.19812 0.1778) (xy -0.2032 0.18796) (xy -0.20701 0.19685) (xy -0.21209 0.20701)
						(xy -0.2159 0.21717) (xy -0.21844 0.22733) (xy -0.22225 0.23876) (xy -0.22352 0.24892) (xy -0.22606 0.25908)
						(xy -0.22733 0.27051) (xy -0.22733 0.28067) (xy -0.2286 0.2921) (xy -0.22733 0.30353) (xy -0.22733 0.31369)
						(xy -0.22606 0.32512) (xy -0.22352 0.33528) (xy -0.22225 0.34544) (xy -0.21844 0.35687) (xy -0.2159 0.36703)
						(xy -0.21209 0.37719) (xy -0.20701 0.38735) (xy -0.2032 0.39624) (xy -0.19812 0.4064) (xy -0.17272 0.44196)
						(xy -0.1651 0.44958) (xy -0.1651 0.7366) (xy -0.16256 0.76835) (xy -0.1524 0.8001) (xy -0.13716 0.82804)
						(xy -0.11684 0.85344) (xy -0.09144 0.87376) (xy -0.0635 0.889) (xy -0.03175 0.89916) (xy 0 0.9017)
						(xy 0.03175 0.89916) (xy 0.0635 0.889) (xy 0.09144 0.87376) (xy 0.11684 0.85344) (xy 0.13716 0.82804)
						(xy 0.1524 0.8001) (xy 0.16256 0.76835) (xy 0.1651 0.7366) (xy 0.1651 0.44958) (xy 0.17272 0.44196)
						(xy 0.19812 0.4064) (xy 0.2032 0.39624) (xy 0.20701 0.38735) (xy 0.21209 0.37719) (xy 0.2159 0.36703)
						(xy 0.21844 0.35687) (xy 0.22225 0.34544) (xy 0.22352 0.33528) (xy 0.22606 0.32512) (xy 0.22733 0.31369)
						(xy 0.22733 0.30353) (xy 0.2286 0.2921) (xy 0.22733 0.28067) (xy 0.22733 0.27051) (xy 0.22606 0.25908)
						(xy 0.22352 0.24892) (xy 0.22225 0.23876) (xy 0.21844 0.22733) (xy 0.2159 0.21717) (xy 0.21209 0.20701)
						(xy 0.20701 0.19685) (xy 0.2032 0.18796) (xy 0.19812 0.1778) (xy 0.17272 0.14224) (xy 0.1651 0.13462)
						(xy 0.1651 -0.7366) (xy 0.16256 -0.76835) (xy 0.1524 -0.8001) (xy 0.13716 -0.82804) (xy 0.11684 -0.85344)
						(xy 0.09144 -0.87376) (xy 0.0635 -0.889) (xy 0.03175 -0.89916)
					)
					(width 0)
					(fill yes)
				)
			)
		)
		(pad "155" smd custom
			(at 16.949928 -4.100068 180)
			(size 0.1143 0.1143)
			(layers "B.Cu" "B.Mask" "B.Paste")
			(net "GND")
			(options
				(clearance outline)
				(anchor circle)
			)
			(primitives
				(gr_poly
					(pts
						(xy 0 -0.9017) (xy -0.03175 -0.89916) (xy -0.0635 -0.889) (xy -0.09144 -0.87376) (xy -0.11684 -0.85344)
						(xy -0.13716 -0.82804) (xy -0.1524 -0.8001) (xy -0.16256 -0.76835) (xy -0.1651 -0.7366) (xy -0.1651 -0.19685)
						(xy -0.17272 -0.18923) (xy -0.17907 -0.18034) (xy -0.18669 -0.17145) (xy -0.19177 -0.16256) (xy -0.19812 -0.15367)
						(xy -0.20828 -0.13335) (xy -0.21971 -0.10287) (xy -0.22225 -0.09271) (xy -0.22479 -0.08128) (xy -0.22606 -0.07112)
						(xy -0.2286 -0.05969) (xy -0.2286 -0.01651) (xy -0.22606 -0.00508) (xy -0.22479 0.00508) (xy -0.22225 0.01651)
						(xy -0.21971 0.02667) (xy -0.20828 0.05715) (xy -0.19812 0.07747) (xy -0.19177 0.08636) (xy -0.18669 0.09525)
						(xy -0.17907 0.10414) (xy -0.17272 0.11303) (xy -0.1651 0.12065) (xy -0.1651 0.7366) (xy -0.16256 0.76835)
						(xy -0.1524 0.8001) (xy -0.13716 0.82804) (xy -0.11684 0.85344) (xy -0.09144 0.87376) (xy -0.0635 0.889)
						(xy -0.03175 0.89916) (xy 0 0.9017) (xy 0.03175 0.89916) (xy 0.0635 0.889) (xy 0.09144 0.87376)
						(xy 0.11684 0.85344) (xy 0.13716 0.82804) (xy 0.1524 0.8001) (xy 0.16256 0.76835) (xy 0.1651 0.7366)
						(xy 0.1651 0.11938) (xy 0.17272 0.11176) (xy 0.19812 0.0762) (xy 0.2032 0.06604) (xy 0.20701 0.05715)
						(xy 0.21209 0.04699) (xy 0.2159 0.03683) (xy 0.21844 0.02667) (xy 0.22225 0.01524) (xy 0.22352 0.00508)
						(xy 0.22606 -0.00508) (xy 0.22733 -0.01651) (xy 0.22733 -0.02667) (xy 0.2286 -0.0381) (xy 0.22733 -0.04953)
						(xy 0.22733 -0.05969) (xy 0.22606 -0.07112) (xy 0.22352 -0.08128) (xy 0.22225 -0.09144) (xy 0.21844 -0.10287)
						(xy 0.2159 -0.11303) (xy 0.21209 -0.12319) (xy 0.20701 -0.13335) (xy 0.2032 -0.14224) (xy 0.19812 -0.1524)
						(xy 0.17272 -0.18796) (xy 0.1651 -0.19558) (xy 0.1651 -0.7366) (xy 0.16256 -0.76835) (xy 0.1524 -0.8001)
						(xy 0.13716 -0.82804) (xy 0.11684 -0.85344) (xy 0.09144 -0.87376) (xy 0.0635 -0.889) (xy 0.03175 -0.89916)
					)
					(width 0)
					(fill yes)
				)
			)
		)
		(pad "156" smd custom
			(at 17.249902 4.100068 180)
			(size 0.1143 0.1143)
			(layers "B.Cu" "B.Mask" "B.Paste")
			(net "M_B_DQS_DP5")
			(options
				(clearance outline)
				(anchor circle)
			)
			(primitives
				(gr_poly
					(pts
						(xy 0 -0.9017) (xy -0.03175 -0.89916) (xy -0.0635 -0.889) (xy -0.09144 -0.87376) (xy -0.11684 -0.85344)
						(xy -0.13716 -0.82804) (xy -0.1524 -0.8001) (xy -0.16256 -0.76835) (xy -0.1651 -0.7366) (xy -0.1651 -0.11938)
						(xy -0.17272 -0.11176) (xy -0.19812 -0.0762) (xy -0.2032 -0.06604) (xy -0.20701 -0.05715) (xy -0.21209 -0.04699)
						(xy -0.2159 -0.03683) (xy -0.21844 -0.02667) (xy -0.22225 -0.01524) (xy -0.22352 -0.00508) (xy -0.22606 0.00508)
						(xy -0.22733 0.01651) (xy -0.22733 0.02667) (xy -0.2286 0.0381) (xy -0.22733 0.04953) (xy -0.22733 0.05969)
						(xy -0.22606 0.07112) (xy -0.22352 0.08128) (xy -0.22225 0.09144) (xy -0.21844 0.10287) (xy -0.2159 0.11303)
						(xy -0.21209 0.12319) (xy -0.20701 0.13335) (xy -0.2032 0.14224) (xy -0.19812 0.1524) (xy -0.17272 0.18796)
						(xy -0.1651 0.19558) (xy -0.1651 0.7366) (xy -0.16256 0.76835) (xy -0.1524 0.8001) (xy -0.13716 0.82804)
						(xy -0.11684 0.85344) (xy -0.09144 0.87376) (xy -0.0635 0.889) (xy -0.03175 0.89916) (xy 0 0.9017)
						(xy 0.03175 0.89916) (xy 0.0635 0.889) (xy 0.09144 0.87376) (xy 0.11684 0.85344) (xy 0.13716 0.82804)
						(xy 0.1524 0.8001) (xy 0.16256 0.76835) (xy 0.1651 0.7366) (xy 0.1651 0.19685) (xy 0.17272 0.18923)
						(xy 0.17907 0.18034) (xy 0.18669 0.17145) (xy 0.19177 0.16256) (xy 0.19812 0.15367) (xy 0.20828 0.13335)
						(xy 0.21971 0.10287) (xy 0.22225 0.09271) (xy 0.22479 0.08128) (xy 0.22606 0.07112) (xy 0.2286 0.05969)
						(xy 0.2286 0.01651) (xy 0.22606 0.00508) (xy 0.22479 -0.00508) (xy 0.22225 -0.01651) (xy 0.21971 -0.02667)
						(xy 0.20828 -0.05715) (xy 0.19812 -0.07747) (xy 0.19177 -0.08636) (xy 0.18669 -0.09525) (xy 0.17907 -0.10414)
						(xy 0.17272 -0.11303) (xy 0.1651 -0.12065) (xy 0.1651 -0.7366) (xy 0.16256 -0.76835) (xy 0.1524 -0.8001)
						(xy 0.13716 -0.82804) (xy 0.11684 -0.85344) (xy 0.09144 -0.87376) (xy 0.0635 -0.889) (xy 0.03175 -0.89916)
					)
					(width 0)
					(fill yes)
				)
			)
		)
		(pad "157" smd custom
			(at 17.549876 -4.100068 180)
			(size 0.1143 0.1143)
			(layers "B.Cu" "B.Mask" "B.Paste")
			(net "GND")
			(options
				(clearance outline)
				(anchor circle)
			)
			(primitives
				(gr_poly
					(pts
						(xy 0 -0.9017) (xy -0.03175 -0.89916) (xy -0.0635 -0.889) (xy -0.09144 -0.87376) (xy -0.11684 -0.85344)
						(xy -0.13716 -0.82804) (xy -0.1524 -0.8001) (xy -0.16256 -0.76835) (xy -0.1651 -0.7366) (xy -0.1651 -0.44958)
						(xy -0.17272 -0.44196) (xy -0.19812 -0.4064) (xy -0.2032 -0.39624) (xy -0.20701 -0.38735) (xy -0.21209 -0.37719)
						(xy -0.2159 -0.36703) (xy -0.21844 -0.35687) (xy -0.22225 -0.34544) (xy -0.22352 -0.33528) (xy -0.22606 -0.32512)
						(xy -0.22733 -0.31369) (xy -0.22733 -0.30353) (xy -0.2286 -0.2921) (xy -0.22733 -0.28067) (xy -0.22733 -0.27051)
						(xy -0.22606 -0.25908) (xy -0.22352 -0.24892) (xy -0.22225 -0.23876) (xy -0.21844 -0.22733) (xy -0.2159 -0.21717)
						(xy -0.21209 -0.20701) (xy -0.20701 -0.19685) (xy -0.2032 -0.18796) (xy -0.19812 -0.1778) (xy -0.17272 -0.14224)
						(xy -0.1651 -0.13462) (xy -0.1651 0.7366) (xy -0.16256 0.76835) (xy -0.1524 0.8001) (xy -0.13716 0.82804)
						(xy -0.11684 0.85344) (xy -0.09144 0.87376) (xy -0.0635 0.889) (xy -0.03175 0.89916) (xy 0 0.9017)
						(xy 0.03175 0.89916) (xy 0.0635 0.889) (xy 0.09144 0.87376) (xy 0.11684 0.85344) (xy 0.13716 0.82804)
						(xy 0.1524 0.8001) (xy 0.16256 0.76835) (xy 0.1651 0.7366) (xy 0.1651 -0.13462) (xy 0.17272 -0.14224)
						(xy 0.19812 -0.1778) (xy 0.2032 -0.18796) (xy 0.20701 -0.19685) (xy 0.21209 -0.20701) (xy 0.2159 -0.21717)
						(xy 0.21844 -0.22733) (xy 0.22225 -0.23876) (xy 0.22352 -0.24892) (xy 0.22606 -0.25908) (xy 0.22733 -0.27051)
						(xy 0.22733 -0.28067) (xy 0.2286 -0.2921) (xy 0.22733 -0.30353) (xy 0.22733 -0.31369) (xy 0.22606 -0.32512)
						(xy 0.22352 -0.33528) (xy 0.22225 -0.34544) (xy 0.21844 -0.35687) (xy 0.2159 -0.36703) (xy 0.21209 -0.37719)
						(xy 0.20701 -0.38735) (xy 0.2032 -0.39624) (xy 0.19812 -0.4064) (xy 0.17272 -0.44196) (xy 0.1651 -0.44958)
						(xy 0.1651 -0.7366) (xy 0.16256 -0.76835) (xy 0.1524 -0.8001) (xy 0.13716 -0.82804) (xy 0.11684 -0.85344)
						(xy 0.09144 -0.87376) (xy 0.0635 -0.889) (xy 0.03175 -0.89916)
					)
					(width 0)
					(fill yes)
				)
			)
		)
		(pad "158" smd custom
			(at 17.850104 4.100068 180)
			(size 0.1143 0.1143)
			(layers "B.Cu" "B.Mask" "B.Paste")
			(net "GND")
			(options
				(clearance outline)
				(anchor circle)
			)
			(primitives
				(gr_poly
					(pts
						(xy 0 -0.9017) (xy -0.03175 -0.89916) (xy -0.0635 -0.889) (xy -0.09144 -0.87376) (xy -0.11684 -0.85344)
						(xy -0.13716 -0.82804) (xy -0.1524 -0.8001) (xy -0.16256 -0.76835) (xy -0.1651 -0.7366) (xy -0.1651 0.13462)
						(xy -0.17272 0.14224) (xy -0.19812 0.1778) (xy -0.2032 0.18796) (xy -0.20701 0.19685) (xy -0.21209 0.20701)
						(xy -0.2159 0.21717) (xy -0.21844 0.22733) (xy -0.22225 0.23876) (xy -0.22352 0.24892) (xy -0.22606 0.25908)
						(xy -0.22733 0.27051) (xy -0.22733 0.28067) (xy -0.2286 0.2921) (xy -0.22733 0.30353) (xy -0.22733 0.31369)
						(xy -0.22606 0.32512) (xy -0.22352 0.33528) (xy -0.22225 0.34544) (xy -0.21844 0.35687) (xy -0.2159 0.36703)
						(xy -0.21209 0.37719) (xy -0.20701 0.38735) (xy -0.2032 0.39624) (xy -0.19812 0.4064) (xy -0.17272 0.44196)
						(xy -0.1651 0.44958) (xy -0.1651 0.7366) (xy -0.16256 0.76835) (xy -0.1524 0.8001) (xy -0.13716 0.82804)
						(xy -0.11684 0.85344) (xy -0.09144 0.87376) (xy -0.0635 0.889) (xy -0.03175 0.89916) (xy 0 0.9017)
						(xy 0.03175 0.89916) (xy 0.0635 0.889) (xy 0.09144 0.87376) (xy 0.11684 0.85344) (xy 0.13716 0.82804)
						(xy 0.1524 0.8001) (xy 0.16256 0.76835) (xy 0.1651 0.7366) (xy 0.1651 0.44958) (xy 0.17272 0.44196)
						(xy 0.19812 0.4064) (xy 0.2032 0.39624) (xy 0.20701 0.38735) (xy 0.21209 0.37719) (xy 0.2159 0.36703)
						(xy 0.21844 0.35687) (xy 0.22225 0.34544) (xy 0.22352 0.33528) (xy 0.22606 0.32512) (xy 0.22733 0.31369)
						(xy 0.22733 0.30353) (xy 0.2286 0.2921) (xy 0.22733 0.28067) (xy 0.22733 0.27051) (xy 0.22606 0.25908)
						(xy 0.22352 0.24892) (xy 0.22225 0.23876) (xy 0.21844 0.22733) (xy 0.2159 0.21717) (xy 0.21209 0.20701)
						(xy 0.20701 0.19685) (xy 0.2032 0.18796) (xy 0.19812 0.1778) (xy 0.17272 0.14224) (xy 0.1651 0.13462)
						(xy 0.1651 -0.7366) (xy 0.16256 -0.76835) (xy 0.1524 -0.8001) (xy 0.13716 -0.82804) (xy 0.11684 -0.85344)
						(xy 0.09144 -0.87376) (xy 0.0635 -0.889) (xy 0.03175 -0.89916)
					)
					(width 0)
					(fill yes)
				)
			)
		)
		(pad "159" smd custom
			(at 18.150078 -4.100068 180)
			(size 0.1143 0.1143)
			(layers "B.Cu" "B.Mask" "B.Paste")
			(net "M_B_DQ42")
			(options
				(clearance outline)
				(anchor circle)
			)
			(primitives
				(gr_poly
					(pts
						(xy 0 -0.9017) (xy -0.03175 -0.89916) (xy -0.0635 -0.889) (xy -0.09144 -0.87376) (xy -0.11684 -0.85344)
						(xy -0.13716 -0.82804) (xy -0.1524 -0.8001) (xy -0.16256 -0.76835) (xy -0.1651 -0.7366) (xy -0.1651 -0.19685)
						(xy -0.17272 -0.18923) (xy -0.17907 -0.18034) (xy -0.18669 -0.17145) (xy -0.19177 -0.16256) (xy -0.19812 -0.15367)
						(xy -0.20828 -0.13335) (xy -0.21971 -0.10287) (xy -0.22225 -0.09271) (xy -0.22479 -0.08128) (xy -0.22606 -0.07112)
						(xy -0.2286 -0.05969) (xy -0.2286 -0.01651) (xy -0.22606 -0.00508) (xy -0.22479 0.00508) (xy -0.22225 0.01651)
						(xy -0.21971 0.02667) (xy -0.20828 0.05715) (xy -0.19812 0.07747) (xy -0.19177 0.08636) (xy -0.18669 0.09525)
						(xy -0.17907 0.10414) (xy -0.17272 0.11303) (xy -0.1651 0.12065) (xy -0.1651 0.7366) (xy -0.16256 0.76835)
						(xy -0.1524 0.8001) (xy -0.13716 0.82804) (xy -0.11684 0.85344) (xy -0.09144 0.87376) (xy -0.0635 0.889)
						(xy -0.03175 0.89916) (xy 0 0.9017) (xy 0.03175 0.89916) (xy 0.0635 0.889) (xy 0.09144 0.87376)
						(xy 0.11684 0.85344) (xy 0.13716 0.82804) (xy 0.1524 0.8001) (xy 0.16256 0.76835) (xy 0.1651 0.7366)
						(xy 0.1651 0.11938) (xy 0.17272 0.11176) (xy 0.19812 0.0762) (xy 0.2032 0.06604) (xy 0.20701 0.05715)
						(xy 0.21209 0.04699) (xy 0.2159 0.03683) (xy 0.21844 0.02667) (xy 0.22225 0.01524) (xy 0.22352 0.00508)
						(xy 0.22606 -0.00508) (xy 0.22733 -0.01651) (xy 0.22733 -0.02667) (xy 0.2286 -0.0381) (xy 0.22733 -0.04953)
						(xy 0.22733 -0.05969) (xy 0.22606 -0.07112) (xy 0.22352 -0.08128) (xy 0.22225 -0.09144) (xy 0.21844 -0.10287)
						(xy 0.2159 -0.11303) (xy 0.21209 -0.12319) (xy 0.20701 -0.13335) (xy 0.2032 -0.14224) (xy 0.19812 -0.1524)
						(xy 0.17272 -0.18796) (xy 0.1651 -0.19558) (xy 0.1651 -0.7366) (xy 0.16256 -0.76835) (xy 0.1524 -0.8001)
						(xy 0.13716 -0.82804) (xy 0.11684 -0.85344) (xy 0.09144 -0.87376) (xy 0.0635 -0.889) (xy 0.03175 -0.89916)
					)
					(width 0)
					(fill yes)
				)
			)
		)
		(pad "160" smd custom
			(at 18.450052 4.100068 180)
			(size 0.1143 0.1143)
			(layers "B.Cu" "B.Mask" "B.Paste")
			(net "M_B_DQ46")
			(options
				(clearance outline)
				(anchor circle)
			)
			(primitives
				(gr_poly
					(pts
						(xy 0 -0.9017) (xy -0.03175 -0.89916) (xy -0.0635 -0.889) (xy -0.09144 -0.87376) (xy -0.11684 -0.85344)
						(xy -0.13716 -0.82804) (xy -0.1524 -0.8001) (xy -0.16256 -0.76835) (xy -0.1651 -0.7366) (xy -0.1651 -0.11938)
						(xy -0.17272 -0.11176) (xy -0.19812 -0.0762) (xy -0.2032 -0.06604) (xy -0.20701 -0.05715) (xy -0.21209 -0.04699)
						(xy -0.2159 -0.03683) (xy -0.21844 -0.02667) (xy -0.22225 -0.01524) (xy -0.22352 -0.00508) (xy -0.22606 0.00508)
						(xy -0.22733 0.01651) (xy -0.22733 0.02667) (xy -0.2286 0.0381) (xy -0.22733 0.04953) (xy -0.22733 0.05969)
						(xy -0.22606 0.07112) (xy -0.22352 0.08128) (xy -0.22225 0.09144) (xy -0.21844 0.10287) (xy -0.2159 0.11303)
						(xy -0.21209 0.12319) (xy -0.20701 0.13335) (xy -0.2032 0.14224) (xy -0.19812 0.1524) (xy -0.17272 0.18796)
						(xy -0.1651 0.19558) (xy -0.1651 0.7366) (xy -0.16256 0.76835) (xy -0.1524 0.8001) (xy -0.13716 0.82804)
						(xy -0.11684 0.85344) (xy -0.09144 0.87376) (xy -0.0635 0.889) (xy -0.03175 0.89916) (xy 0 0.9017)
						(xy 0.03175 0.89916) (xy 0.0635 0.889) (xy 0.09144 0.87376) (xy 0.11684 0.85344) (xy 0.13716 0.82804)
						(xy 0.1524 0.8001) (xy 0.16256 0.76835) (xy 0.1651 0.7366) (xy 0.1651 0.19685) (xy 0.17272 0.18923)
						(xy 0.17907 0.18034) (xy 0.18669 0.17145) (xy 0.19177 0.16256) (xy 0.19812 0.15367) (xy 0.20828 0.13335)
						(xy 0.21971 0.10287) (xy 0.22225 0.09271) (xy 0.22479 0.08128) (xy 0.22606 0.07112) (xy 0.2286 0.05969)
						(xy 0.2286 0.01651) (xy 0.22606 0.00508) (xy 0.22479 -0.00508) (xy 0.22225 -0.01651) (xy 0.21971 -0.02667)
						(xy 0.20828 -0.05715) (xy 0.19812 -0.07747) (xy 0.19177 -0.08636) (xy 0.18669 -0.09525) (xy 0.17907 -0.10414)
						(xy 0.17272 -0.11303) (xy 0.1651 -0.12065) (xy 0.1651 -0.7366) (xy 0.16256 -0.76835) (xy 0.1524 -0.8001)
						(xy 0.13716 -0.82804) (xy 0.11684 -0.85344) (xy 0.09144 -0.87376) (xy 0.0635 -0.889) (xy 0.03175 -0.89916)
					)
					(width 0)
					(fill yes)
				)
			)
		)
	)
)
